# BASEBOARD_FAB2 (Tioga Pass) — schematic netlist excerpt (pin names and nets, part order shuffled) for the footprints in the layout excerpt that follows; sources: Cadence DE-HDL packaged netlist, KiCad conversion of Wiwynn_Tioga_Pass_MB.brd

CF8  SC22P50V2JN-4GP  5%  pkg SMD-BCG  page 206 : \1\ = VR_PVCCIN_CPU1_AIREF2 ; \2\ = ISENSE_PVCCIN_CPU1_PH2_IMON
C7F13  CAP  2200PF 50V 10% X7R  pkg 0402LF  page 231 : A = VR_COMP_PVPP_ABC ; B = VR_FB_PVPP_ABC
C7A9  CAP  1.0UF 16V 10% X6S  pkg 0402  page 236 : A = VR_FET_SW_P12V_STBY_PVDDQ_DEF ; B = GND

(kicad_pcb
	(version 20260206)
	(generator "pcbnew")
	(generator_version "10.0")
	(general
		(thickness 1.6)
		(legacy_teardrops no)
	)
	(paper "A4")
	(title_block
		(title "Wiwynn_Tioga_Pass_MB.brd")
		(comment 1 "Tioga Pass / footprints 2327-2329 of 4770")
	)
	(layers
		(0 "F.Cu" signal "TOP")
		(4 "In1.Cu" signal "L2GND")
		(6 "In2.Cu" signal "L3")
		(8 "In3.Cu" signal "L4GND")
		(10 "In4.Cu" signal "L5")
		(12 "In5.Cu" signal "L6GND")
		(14 "In6.Cu" signal "L7VCC")
		(16 "In7.Cu" signal "L8VCC")
		(18 "In8.Cu" signal "L9GND")
		(20 "In9.Cu" signal "L10")
		(22 "In10.Cu" signal "L11GND")
		(24 "In11.Cu" signal "L12")
		(26 "In12.Cu" signal "L13GND")
		(2 "B.Cu" signal "BOTTOM")
		(9 "F.Adhes" user "F.Adhesive")
		(11 "B.Adhes" user "B.Adhesive")
		(13 "F.Paste" user "Package Geometry/Pastemask Top")
		(15 "B.Paste" user "Package Geometry/Pastemask Bottom")
		(5 "F.SilkS" user "Ref Des/Silkscreen Top")
		(7 "B.SilkS" user "Ref Des/Silkscreen Bottom")
		(1 "F.Mask" user "Board Geometry/Soldermask Top")
		(3 "B.Mask" user "Board Geometry/Soldermask Bottom")
		(17 "Dwgs.User" user "User.Drawings")
		(19 "Cmts.User" user "User.Comments")
		(21 "Eco1.User" user "User.Eco1")
		(23 "Eco2.User" user "User.Eco2")
		(25 "Edge.Cuts" user "Board Geometry/Outline")
		(27 "Margin" user)
		(31 "F.CrtYd" user "Package Geometry/Place Bound Top")
		(29 "B.CrtYd" user "Package Geometry/Place Bound Bottom")
		(35 "F.Fab" user "Ref Des/Assembly Top")
		(33 "B.Fab" user "Ref Des/Assembly Bottom")
	)
	(footprint ""
		(layer "F.Cu")
		(at 336.677 -22.352 180)
		(property "Reference" "C7F13"
			(at 0 0 180)
			(layer "F.SilkS")
			(hide yes)
			(effects
				(font
					(size 1.27 1.27)
				)
			)
		)
		(property "Value" ""
			(at 0 0 180)
			(layer "F.Fab")
			(effects
				(font
					(size 1.27 1.27)
				)
			)
		)
		(duplicate_pad_numbers_are_jumpers no)
		(fp_poly
			(pts
				(xy 0.3048 -0.1016) (xy 0.3048 0.9906) (xy -0.3048 0.9906) (xy -0.3048 -0.1016)
			)
			(stroke
				(width 0)
				(type default)
			)
			(fill no)
			(layer "F.CrtYd")
		)
		(fp_line
			(start 0.3048 0.9906)
			(end 0.3048 -0.1016)
			(stroke
				(width 0.1)
				(type default)
			)
			(layer "F.Fab")
		)
		(fp_line
			(start 0.3048 -0.1016)
			(end -0.3048 -0.1016)
			(stroke
				(width 0.1)
				(type default)
			)
			(layer "F.Fab")
		)
		(fp_line
			(start -0.3048 0.9906)
			(end 0.3048 0.9906)
			(stroke
				(width 0.1)
				(type default)
			)
			(layer "F.Fab")
		)
		(fp_line
			(start -0.3048 -0.1016)
			(end -0.3048 0.9906)
			(stroke
				(width 0.1)
				(type default)
			)
			(layer "F.Fab")
		)
		(pad "1" smd rect
			(at 0 0 180)
			(size 0.508 0.508)
			(layers "F.Cu" "F.Mask" "F.Paste")
			(net "VR_COMP_PVPP_ABC")
		)
		(pad "2" smd rect
			(at 0 0.889 180)
			(size 0.508 0.508)
			(layers "F.Cu" "F.Mask" "F.Paste")
			(net "VR_FB_PVPP_ABC")
		)
		(zone
			(layer "F.Cu")
			(hatch none 0.5)
			(connect_pads
				(clearance 0)
			)
			(min_thickness 0.25)
			(keepout
				(tracks not_allowed)
				(vias allowed)
				(pads allowed)
				(copperpour not_allowed)
				(footprints allowed)
			)
			(placement
				(enabled no)
				(sheetname "")
			)
			(fill
				(thermal_gap 0.5)
				(thermal_bridge_width 0.5)
				(island_removal_mode 0)
			)
			(polygon
				(pts
					(xy 336.931 -22.987) (xy 336.423 -22.987) (xy 336.423 -22.606) (xy 336.931 -22.606)
				)
			)
		)
		(zone
			(layer "F.Cu")
			(hatch none 0.5)
			(connect_pads
				(clearance 0)
			)
			(min_thickness 0.25)
			(keepout
				(tracks allowed)
				(vias not_allowed)
				(pads allowed)
				(copperpour not_allowed)
				(footprints allowed)
			)
			(placement
				(enabled no)
				(sheetname "")
			)
			(fill
				(thermal_gap 0.5)
				(thermal_bridge_width 0.5)
				(island_removal_mode 0)
			)
			(polygon
				(pts
					(xy 336.931 -22.606) (xy 336.423 -22.606) (xy 336.423 -22.987) (xy 336.931 -22.987)
				)
			)
		)
	)
	(footprint ""
		(layer "F.Cu")
		(at 25.035002 -88.130634 180)
		(property "Reference" "CF8"
			(at 0 0 180)
			(layer "F.SilkS")
			(hide yes)
			(effects
				(font
					(size 1.27 1.27)
				)
			)
		)
		(property "Value" "*"
			(at 1.1811 -2.8194 180)
			(unlocked yes)
			(layer "F.Fab")
			(hide yes)
			(effects
				(font
					(size 1.27 1.016)
					(thickness 0.1524)
				)
			)
		)
		(property "Device Type" "SC22P50V2JN-4GP_SMD-BCG-SC22P5A"
			(at 1.1811 -4.3434 180)
			(unlocked yes)
			(layer "F.Fab")
			(hide yes)
			(effects
				(font
					(size 1.27 1.016)
					(thickness 0.1524)
				)
			)
		)
		(duplicate_pad_numbers_are_jumpers no)
		(fp_rect
			(start -0.4318 0.9525)
			(end 0.4318 -0.9525)
			(stroke
				(width 0)
				(type default)
			)
			(fill no)
			(layer "F.CrtYd")
		)
		(fp_rect
			(start -0.4318 0.9525)
			(end 0.4318 -0.9525)
			(stroke
				(width 0)
				(type default)
			)
			(fill no)
			(layer "F.Fab")
		)
		(pad "1" smd custom
			(at 0 -0.4445 180)
			(size 0.1524 0.1524)
			(layers "F.Cu" "F.Mask" "F.Paste")
			(net "VR_PVCCIN_CPU1_AIREF2")
			(options
				(clearance outline)
				(anchor circle)
			)
			(primitives
				(gr_poly
					(pts
						(arc
							(start 0.3048 -0.2032)
							(mid 0.275042 -0.275042)
							(end 0.2032 -0.3048)
						)
						(arc
							(start -0.2032 -0.3048)
							(mid -0.275042 -0.275042)
							(end -0.3048 -0.2032)
						)
						(arc
							(start -0.3048 0.2032)
							(mid -0.275042 0.275042)
							(end -0.2032 0.3048)
						)
						(arc
							(start 0.2032 0.3048)
							(mid 0.275042 0.275042)
							(end 0.3048 0.2032)
						)
					)
					(width 0)
					(fill yes)
				)
			)
		)
		(pad "2" smd custom
			(at 0 0.4445 180)
			(size 0.1524 0.1524)
			(layers "F.Cu" "F.Mask" "F.Paste")
			(net "ISENSE_PVCCIN_CPU1_PH2_IMON")
			(options
				(clearance outline)
				(anchor circle)
			)
			(primitives
				(gr_poly
					(pts
						(arc
							(start 0.3048 -0.2032)
							(mid 0.275042 -0.275042)
							(end 0.2032 -0.3048)
						)
						(arc
							(start -0.2032 -0.3048)
							(mid -0.275042 -0.275042)
							(end -0.3048 -0.2032)
						)
						(arc
							(start -0.3048 0.2032)
							(mid -0.275042 0.275042)
							(end -0.2032 0.3048)
						)
						(arc
							(start 0.2032 0.3048)
							(mid 0.275042 0.275042)
							(end 0.3048 0.2032)
						)
					)
					(width 0)
					(fill yes)
				)
			)
		)
	)
	(footprint ""
		(layer "F.Cu")
		(at 388.992618 -156.591 90)
		(property "Reference" "C7A9"
			(at 0 0 90)
			(layer "F.SilkS")
			(hide yes)
			(effects
				(font
					(size 1.27 1.27)
				)
			)
		)
		(property "Value" ""
			(at 0 0 90)
			(layer "F.Fab")
			(effects
				(font
					(size 1.27 1.27)
				)
			)
		)
		(duplicate_pad_numbers_are_jumpers no)
		(fp_poly
			(pts
				(xy 0.3048 -0.1016) (xy 0.3048 0.9906) (xy -0.3048 0.9906) (xy -0.3048 -0.1016)
			)
			(stroke
				(width 0)
				(type default)
			)
			(fill no)
			(layer "F.CrtYd")
		)
		(fp_line
			(start 0.3048 -0.1016)
			(end -0.3048 -0.1016)
			(stroke
				(width 0.1)
				(type default)
			)
			(layer "F.Fab")
		)
		(fp_line
			(start -0.3048 -0.1016)
			(end -0.3048 0.9906)
			(stroke
				(width 0.1)
				(type default)
			)
			(layer "F.Fab")
		)
		(fp_line
			(start 0.3048 0.9906)
			(end 0.3048 -0.1016)
			(stroke
				(width 0.1)
				(type default)
			)
			(layer "F.Fab")
		)
		(fp_line
			(start -0.3048 0.9906)
			(end 0.3048 0.9906)
			(stroke
				(width 0.1)
				(type default)
			)
			(layer "F.Fab")
		)
		(pad "1" smd rect
			(at 0 0 90)
			(size 0.508 0.508)
			(layers "F.Cu" "F.Mask" "F.Paste")
			(net "VR_FET_SW_P12V_STBY_PVDDQ_DEF")
		)
		(pad "2" smd rect
			(at 0 0.889 90)
			(size 0.508 0.508)
			(layers "F.Cu" "F.Mask" "F.Paste")
			(net "GND")
		)
		(zone
			(layer "F.Cu")
			(hatch none 0.5)
			(connect_pads
				(clearance 0)
			)
			(min_thickness 0.25)
			(keepout
				(tracks allowed)
				(vias not_allowed)
				(pads allowed)
				(copperpour not_allowed)
				(footprints allowed)
			)
			(placement
				(enabled no)
				(sheetname "")
			)
			(fill
				(thermal_gap 0.5)
				(thermal_bridge_width 0.5)
				(island_removal_mode 0)
			)
			(polygon
				(pts
					(xy 389.246618 -156.337) (xy 389.246618 -156.845) (xy 389.627618 -156.845) (xy 389.627618 -156.337)
				)
			)
		)
		(zone
			(layer "F.Cu")
			(hatch none 0.5)
			(connect_pads
				(clearance 0)
			)
			(min_thickness 0.25)
			(keepout
				(tracks not_allowed)
				(vias allowed)
				(pads allowed)
				(copperpour not_allowed)
				(footprints allowed)
			)
			(placement
				(enabled no)
				(sheetname "")
			)
			(fill
				(thermal_gap 0.5)
				(thermal_bridge_width 0.5)
				(island_removal_mode 0)
			)
			(polygon
				(pts
					(xy 389.627618 -156.337) (xy 389.627618 -156.845) (xy 389.246618 -156.845) (xy 389.246618 -156.337)
				)
			)
		)
	)
)
